# T6G (Grand Teton) — schematic netlist excerpt (pin names and nets, part order shuffled) for the footprints in the layout excerpt that follows; sources: Cadence DE-HDL packaged netlist, KiCad conversion of 04192023_DAF0TMB3IC0_F0TG_MB_C_brd_V02_OCP.brd

U64  M24128BWMN6TP  M24128-BWMN6TP IC  pkg SOIC8XH  page 238
  E0  = MB_FRU_ADDR0
  E1  = MB_FRU_ADDR1
  E2  = MB_FRU_ADDR2
  VSS  = GND
  SDA  = SMB_FRU_3V3AUX_R1_SDA
  SCL  = SMB_FRU_3V3AUX_R1_SCL
  \wc#\  = PD_MB_FRU_WP
  VCC  = P3V3_AUX

C1663  Q_CAP  0.1UF 25V 10% X7R  pkg 0402  page 133 : A = P3V3_AUX ; B = GND

(kicad_pcb
	(version 20260206)
	(generator "pcbnew")
	(generator_version "10.0")
	(general
		(thickness 1.6)
		(legacy_teardrops no)
	)
	(paper "A4")
	(title_block
		(title "04192023_DAF0TMB3IC0_F0TG_MB_C_brd_V02_OCP.brd")
		(comment 1 "Grand Teton / footprints 1219-1221 of 8354")
	)
	(layers
		(0 "F.Cu" signal "TOP")
		(4 "In1.Cu" signal "GND")
		(6 "In2.Cu" signal "IN1")
		(8 "In3.Cu" signal "GND1")
		(10 "In4.Cu" signal "IN2")
		(12 "In5.Cu" signal "GND2")
		(14 "In6.Cu" signal "IN3")
		(16 "In7.Cu" signal "GND3")
		(18 "In8.Cu" signal "VCC")
		(20 "In9.Cu" signal "VCC1")
		(22 "In10.Cu" signal "GND4")
		(24 "In11.Cu" signal "IN4")
		(26 "In12.Cu" signal "GND5")
		(28 "In13.Cu" signal "IN5")
		(30 "In14.Cu" signal "GND6")
		(32 "In15.Cu" signal "IN6")
		(34 "In16.Cu" signal "GND7")
		(2 "B.Cu" signal "BOTTOM")
		(9 "F.Adhes" user "F.Adhesive")
		(11 "B.Adhes" user "B.Adhesive")
		(13 "F.Paste" user "Package Geometry/Pastemask Top")
		(15 "B.Paste" user "Package Geometry/Pastemask Bottom")
		(5 "F.SilkS" user "Ref Des/Silkscreen Top")
		(7 "B.SilkS" user "Ref Des/Silkscreen Bottom")
		(1 "F.Mask" user "Board Geometry/Soldermask Top")
		(3 "B.Mask" user "Board Geometry/Soldermask Bottom")
		(17 "Dwgs.User" user "User.Drawings")
		(19 "Cmts.User" user "User.Comments")
		(21 "Eco1.User" user "User.Eco1")
		(23 "Eco2.User" user "User.Eco2")
		(25 "Edge.Cuts" user "Board Geometry/Outline")
		(27 "Margin" user)
		(31 "F.CrtYd" user "Package Geometry/Place Bound Top")
		(29 "B.CrtYd" user "Package Geometry/Place Bound Bottom")
		(35 "F.Fab" user "Ref Des/Assembly Top")
		(33 "B.Fab" user "Ref Des/Assembly Bottom")
	)
	(footprint ""
		(layer "F.Cu")
		(at 161.30524 -36.739322 90)
		(property "Reference" "C1663"
			(at 0 0 90)
			(layer "F.SilkS")
			(hide yes)
			(effects
				(font
					(size 1.27 1.27)
				)
			)
		)
		(property "Value" ""
			(at 0 0 90)
			(layer "F.Fab")
			(effects
				(font
					(size 1.27 1.27)
				)
			)
		)
		(duplicate_pad_numbers_are_jumpers no)
		(fp_line
			(start 0.7874 -0.4064)
			(end 0.7874 0.4064)
			(stroke
				(width 0.1524)
				(type default)
			)
			(layer "F.SilkS")
		)
		(fp_line
			(start -0.7874 -0.4064)
			(end 0.7874 -0.4064)
			(stroke
				(width 0.1524)
				(type default)
			)
			(layer "F.SilkS")
		)
		(fp_line
			(start 0.7874 0.4064)
			(end -0.7874 0.4064)
			(stroke
				(width 0.1524)
				(type default)
			)
			(layer "F.SilkS")
		)
		(fp_line
			(start -0.7874 0.4064)
			(end -0.7874 -0.4064)
			(stroke
				(width 0.1524)
				(type default)
			)
			(layer "F.SilkS")
		)
		(fp_line
			(start -0.12065 -0.305054)
			(end -0.12065 -0.2794)
			(stroke
				(width 0.1)
				(type default)
			)
			(layer "F.Fab")
		)
		(fp_line
			(start -0.67945 -0.305054)
			(end -0.12065 -0.305054)
			(stroke
				(width 0.1)
				(type default)
			)
			(layer "F.Fab")
		)
		(fp_line
			(start 0.67945 -0.3048)
			(end 0.67945 0.3048)
			(stroke
				(width 0.1)
				(type default)
			)
			(layer "F.Fab")
		)
		(fp_line
			(start 0.12065 -0.3048)
			(end 0.67945 -0.3048)
			(stroke
				(width 0.1)
				(type default)
			)
			(layer "F.Fab")
		)
		(fp_line
			(start 0.12065 -0.2794)
			(end 0.12065 -0.3048)
			(stroke
				(width 0.1)
				(type default)
			)
			(layer "F.Fab")
		)
		(fp_line
			(start -0.12065 -0.2794)
			(end 0.12065 -0.2794)
			(stroke
				(width 0.1)
				(type default)
			)
			(layer "F.Fab")
		)
		(fp_line
			(start 0.120396 0.2794)
			(end -0.12065 0.2794)
			(stroke
				(width 0.1)
				(type default)
			)
			(layer "F.Fab")
		)
		(fp_line
			(start -0.12065 0.2794)
			(end -0.12065 0.3048)
			(stroke
				(width 0.1)
				(type default)
			)
			(layer "F.Fab")
		)
		(fp_line
			(start 0.67945 0.3048)
			(end 0.120396 0.3048)
			(stroke
				(width 0.1)
				(type default)
			)
			(layer "F.Fab")
		)
		(fp_line
			(start 0.120396 0.3048)
			(end 0.120396 0.2794)
			(stroke
				(width 0.1)
				(type default)
			)
			(layer "F.Fab")
		)
		(fp_line
			(start -0.12065 0.3048)
			(end -0.67945 0.3048)
			(stroke
				(width 0.1)
				(type default)
			)
			(layer "F.Fab")
		)
		(fp_line
			(start -0.67945 0.3048)
			(end -0.67945 -0.305054)
			(stroke
				(width 0.1)
				(type default)
			)
			(layer "F.Fab")
		)
		(pad "1" smd circle
			(at -0.40005 0 90)
			(size 0 0)
			(layers "F.Cu" "F.Mask" "F.Paste")
			(net "P3V3_AUX")
		)
		(pad "2" smd circle
			(at 0.40005 0 90)
			(size 0 0)
			(layers "F.Cu" "F.Mask" "F.Paste")
			(net "GND")
		)
	)
	(footprint ""
		(layer "F.Cu")
		(at 51.698906 19.444716 -90)
		(property "Reference" "JP4003_12"
			(at 0 0 270)
			(layer "F.SilkS")
			(hide yes)
			(effects
				(font
					(size 1.27 1.27)
				)
			)
		)
		(property "Value" ""
			(at 0 0 270)
			(layer "F.Fab")
			(effects
				(font
					(size 1.27 1.27)
				)
			)
		)
		(duplicate_pad_numbers_are_jumpers no)
		(pad "1" smd circle
			(at 0 0 270)
			(size 0.762 0.762)
			(layers "F.Cu" "F.Mask" "F.Paste")
			(net "Net_10793")
		)
	)
	(footprint ""
		(layer "F.Cu")
		(at 311.937908 -117.570504)
		(property "Reference" "U64"
			(at -1.32842 -3.188208 0)
			(unlocked yes)
			(layer "F.SilkS")
			(effects
				(font
					(size 0.7874 0.5842)
					(thickness 0.1524)
				)
				(justify left)
			)
		)
		(property "Value" ""
			(at 0 0 0)
			(layer "F.Fab")
			(effects
				(font
					(size 1.27 1.27)
				)
			)
		)
		(duplicate_pad_numbers_are_jumpers no)
		(fp_line
			(start -1.8288 -2.500122)
			(end -1.8288 2.500122)
			(stroke
				(width 0.1524)
				(type default)
			)
			(layer "F.SilkS")
		)
		(fp_line
			(start -1.8288 2.500122)
			(end 1.8288 2.500122)
			(stroke
				(width 0.1524)
				(type default)
			)
			(layer "F.SilkS")
		)
		(fp_line
			(start -1.077722 -2.500122)
			(end -1.8288 -2.500122)
			(stroke
				(width 0.1524)
				(type default)
			)
			(layer "F.SilkS")
		)
		(fp_line
			(start 0 -1.4224)
			(end -1.077722 -2.500122)
			(stroke
				(width 0.1524)
				(type default)
			)
			(layer "F.SilkS")
		)
		(fp_line
			(start 1.077722 -2.500122)
			(end 0 -1.4224)
			(stroke
				(width 0.1524)
				(type default)
			)
			(layer "F.SilkS")
		)
		(fp_line
			(start 1.8288 -2.500122)
			(end 1.077722 -2.500122)
			(stroke
				(width 0.1524)
				(type default)
			)
			(layer "F.SilkS")
		)
		(fp_line
			(start 1.8288 2.500122)
			(end 1.8288 -2.500122)
			(stroke
				(width 0.1524)
				(type default)
			)
			(layer "F.SilkS")
		)
		(fp_poly
			(pts
				(xy -2.792984 -3.610102) (xy -3.300984 -4.626102) (xy -2.284984 -4.626102)
			)
			(stroke
				(width 0)
				(type default)
			)
			(fill yes)
			(layer "F.SilkS")
		)
		(fp_line
			(start -1.999996 -2.500122)
			(end -1.999996 2.500122)
			(stroke
				(width 0.1)
				(type default)
			)
			(layer "F.Fab")
		)
		(fp_line
			(start -1.999996 2.500122)
			(end 1.999996 2.500122)
			(stroke
				(width 0.1)
				(type default)
			)
			(layer "F.Fab")
		)
		(fp_line
			(start 1.999996 -2.500122)
			(end -1.999996 -2.500122)
			(stroke
				(width 0.1)
				(type default)
			)
			(layer "F.Fab")
		)
		(fp_line
			(start 1.999996 2.500122)
			(end 1.999996 -2.500122)
			(stroke
				(width 0.1)
				(type default)
			)
			(layer "F.Fab")
		)
		(fp_poly
			(pts
				(xy -4.5085 -2.413) (xy -4.5085 -1.397) (xy -3.4925 -1.905)
			)
			(stroke
				(width 0)
				(type default)
			)
			(fill yes)
			(layer "F.Fab")
		)
		(pad "1" smd rect
			(at -2.599944 -1.905 270)
			(size 0.889 1.27)
			(layers "F.Cu" "F.Mask" "F.Paste")
			(net "MB_FRU_ADDR0")
		)
		(pad "2" smd rect
			(at -2.599944 -0.635 270)
			(size 0.889 1.27)
			(layers "F.Cu" "F.Mask" "F.Paste")
			(net "MB_FRU_ADDR1")
		)
		(pad "3" smd rect
			(at -2.599944 0.635 270)
			(size 0.889 1.27)
			(layers "F.Cu" "F.Mask" "F.Paste")
			(net "MB_FRU_ADDR2")
		)
		(pad "4" smd rect
			(at -2.599944 1.905 270)
			(size 0.889 1.27)
			(layers "F.Cu" "F.Mask" "F.Paste")
			(net "GND")
		)
		(pad "5" smd rect
			(at 2.599944 1.905 270)
			(size 0.889 1.27)
			(layers "F.Cu" "F.Mask" "F.Paste")
			(net "SMB_FRU_3V3AUX_R1_SDA")
		)
		(pad "6" smd rect
			(at 2.599944 0.635 270)
			(size 0.889 1.27)
			(layers "F.Cu" "F.Mask" "F.Paste")
			(net "SMB_FRU_3V3AUX_R1_SCL")
		)
		(pad "7" smd rect
			(at 2.599944 -0.635 270)
			(size 0.889 1.27)
			(layers "F.Cu" "F.Mask" "F.Paste")
			(net "PD_MB_FRU_WP")
		)
		(pad "8" smd rect
			(at 2.599944 -1.905 270)
			(size 0.889 1.27)
			(layers "F.Cu" "F.Mask" "F.Paste")
			(net "P3V3_AUX")
		)
	)
)
